# T6G (Grand Teton) — schematic netlist excerpt (pin names and nets, part order shuffled) for the footprints in the layout excerpt that follows; sources: Cadence DE-HDL packaged netlist, KiCad conversion of 04192023_DAF0TMB3IC0_F0TG_MB_C_brd_V02_OCP.brd

H13  HOLE  EMPTY  pkg TH  page 230 : \1\ = GND
C5017  Q_CAP  1000PF 50V 5% X7R  pkg 0402  page 193 : A = GND ; B = PWRGD_PVDDCR_CPU0_P0
PR423  Q_RES  8.87K 1% EMPTY  pkg 0402LF  page 213 : A = GND ; B = PVDDCR_CPU0_P1_LSET6

(kicad_pcb
	(version 20260206)
	(generator "pcbnew")
	(generator_version "10.0")
	(general
		(thickness 1.6)
		(legacy_teardrops no)
	)
	(paper "A4")
	(title_block
		(title "04192023_DAF0TMB3IC0_F0TG_MB_C_brd_V02_OCP.brd")
		(comment 1 "Grand Teton / footprints 4737-4739 of 8354")
	)
	(layers
		(0 "F.Cu" signal "TOP")
		(4 "In1.Cu" signal "GND")
		(6 "In2.Cu" signal "IN1")
		(8 "In3.Cu" signal "GND1")
		(10 "In4.Cu" signal "IN2")
		(12 "In5.Cu" signal "GND2")
		(14 "In6.Cu" signal "IN3")
		(16 "In7.Cu" signal "GND3")
		(18 "In8.Cu" signal "VCC")
		(20 "In9.Cu" signal "VCC1")
		(22 "In10.Cu" signal "GND4")
		(24 "In11.Cu" signal "IN4")
		(26 "In12.Cu" signal "GND5")
		(28 "In13.Cu" signal "IN5")
		(30 "In14.Cu" signal "GND6")
		(32 "In15.Cu" signal "IN6")
		(34 "In16.Cu" signal "GND7")
		(2 "B.Cu" signal "BOTTOM")
		(9 "F.Adhes" user "F.Adhesive")
		(11 "B.Adhes" user "B.Adhesive")
		(13 "F.Paste" user "Package Geometry/Pastemask Top")
		(15 "B.Paste" user "Package Geometry/Pastemask Bottom")
		(5 "F.SilkS" user "Ref Des/Silkscreen Top")
		(7 "B.SilkS" user "Ref Des/Silkscreen Bottom")
		(1 "F.Mask" user "Board Geometry/Soldermask Top")
		(3 "B.Mask" user "Board Geometry/Soldermask Bottom")
		(17 "Dwgs.User" user "User.Drawings")
		(19 "Cmts.User" user "User.Comments")
		(21 "Eco1.User" user "User.Eco1")
		(23 "Eco2.User" user "User.Eco2")
		(25 "Edge.Cuts" user "Board Geometry/Outline")
		(27 "Margin" user)
		(31 "F.CrtYd" user "Package Geometry/Place Bound Top")
		(29 "B.CrtYd" user "Package Geometry/Place Bound Bottom")
		(35 "F.Fab" user "Ref Des/Assembly Top")
		(33 "B.Fab" user "Ref Des/Assembly Bottom")
	)
	(footprint ""
		(layer "F.Cu")
		(at 371.921278 -136.608058 180)
		(property "Reference" "C5017"
			(at 0 0 180)
			(layer "F.SilkS")
			(hide yes)
			(effects
				(font
					(size 1.27 1.27)
				)
			)
		)
		(property "Value" ""
			(at 0 0 180)
			(layer "F.Fab")
			(effects
				(font
					(size 1.27 1.27)
				)
			)
		)
		(duplicate_pad_numbers_are_jumpers no)
		(fp_line
			(start 0.7874 0.4064)
			(end -0.7874 0.4064)
			(stroke
				(width 0.1524)
				(type default)
			)
			(layer "F.SilkS")
		)
		(fp_line
			(start 0.7874 -0.4064)
			(end 0.7874 0.4064)
			(stroke
				(width 0.1524)
				(type default)
			)
			(layer "F.SilkS")
		)
		(fp_line
			(start -0.7874 0.4064)
			(end -0.7874 -0.4064)
			(stroke
				(width 0.1524)
				(type default)
			)
			(layer "F.SilkS")
		)
		(fp_line
			(start -0.7874 -0.4064)
			(end 0.7874 -0.4064)
			(stroke
				(width 0.1524)
				(type default)
			)
			(layer "F.SilkS")
		)
		(fp_line
			(start 0.67945 0.3048)
			(end 0.120396 0.3048)
			(stroke
				(width 0.1)
				(type default)
			)
			(layer "F.Fab")
		)
		(fp_line
			(start 0.67945 -0.3048)
			(end 0.67945 0.3048)
			(stroke
				(width 0.1)
				(type default)
			)
			(layer "F.Fab")
		)
		(fp_line
			(start 0.12065 -0.2794)
			(end 0.12065 -0.3048)
			(stroke
				(width 0.1)
				(type default)
			)
			(layer "F.Fab")
		)
		(fp_line
			(start 0.12065 -0.3048)
			(end 0.67945 -0.3048)
			(stroke
				(width 0.1)
				(type default)
			)
			(layer "F.Fab")
		)
		(fp_line
			(start 0.120396 0.3048)
			(end 0.120396 0.2794)
			(stroke
				(width 0.1)
				(type default)
			)
			(layer "F.Fab")
		)
		(fp_line
			(start 0.120396 0.2794)
			(end -0.12065 0.2794)
			(stroke
				(width 0.1)
				(type default)
			)
			(layer "F.Fab")
		)
		(fp_line
			(start -0.12065 0.3048)
			(end -0.67945 0.3048)
			(stroke
				(width 0.1)
				(type default)
			)
			(layer "F.Fab")
		)
		(fp_line
			(start -0.12065 0.2794)
			(end -0.12065 0.3048)
			(stroke
				(width 0.1)
				(type default)
			)
			(layer "F.Fab")
		)
		(fp_line
			(start -0.12065 -0.2794)
			(end 0.12065 -0.2794)
			(stroke
				(width 0.1)
				(type default)
			)
			(layer "F.Fab")
		)
		(fp_line
			(start -0.12065 -0.305054)
			(end -0.12065 -0.2794)
			(stroke
				(width 0.1)
				(type default)
			)
			(layer "F.Fab")
		)
		(fp_line
			(start -0.67945 0.3048)
			(end -0.67945 -0.305054)
			(stroke
				(width 0.1)
				(type default)
			)
			(layer "F.Fab")
		)
		(fp_line
			(start -0.67945 -0.305054)
			(end -0.12065 -0.305054)
			(stroke
				(width 0.1)
				(type default)
			)
			(layer "F.Fab")
		)
		(pad "1" smd circle
			(at -0.40005 0 180)
			(size 0 0)
			(layers "F.Cu" "F.Mask" "F.Paste")
			(net "GND")
		)
		(pad "2" smd circle
			(at 0.40005 0 180)
			(size 0 0)
			(layers "F.Cu" "F.Mask" "F.Paste")
			(net "PWRGD_PVDDCR_CPU0_P0")
		)
	)
	(footprint ""
		(layer "F.Cu")
		(at 70.21576 -344.814906)
		(property "Reference" "H13"
			(at -2.6416 -4.08813 0)
			(unlocked yes)
			(layer "F.SilkS")
			(effects
				(font
					(size 0.7874 0.5842)
					(thickness 0.1524)
				)
				(justify left)
			)
		)
		(property "Value" ""
			(at 0 0 0)
			(layer "F.Fab")
			(effects
				(font
					(size 1.27 1.27)
				)
			)
		)
		(duplicate_pad_numbers_are_jumpers no)
		(pad "1" thru_hole circle
			(at 0 0)
			(size 6.1976 6.1976)
			(drill 3.7338)
			(layers "*.Cu" "*.Mask")
			(remove_unused_layers no)
			(net "GND")
			(clearance -0.9779)
			(padstack
				(mode front_inner_back)
				(layer "Inner"
					(shape circle)
					(size 5.5372 5.5372)
					(clearance -0.6477)
				)
				(layer "B.Cu"
					(shape circle)
					(size 6.1976 6.1976)
					(clearance -0.9779)
				)
			)
		)
	)
	(footprint ""
		(layer "F.Cu")
		(at 66.952114 -163.71697)
		(property "Reference" "PR423"
			(at 0 0 0)
			(layer "F.SilkS")
			(hide yes)
			(effects
				(font
					(size 1.27 1.27)
				)
			)
		)
		(property "Value" ""
			(at 0 0 0)
			(layer "F.Fab")
			(effects
				(font
					(size 1.27 1.27)
				)
			)
		)
		(duplicate_pad_numbers_are_jumpers no)
		(fp_line
			(start -0.7874 -0.4064)
			(end 0.7874 -0.4064)
			(stroke
				(width 0.1524)
				(type default)
			)
			(layer "F.SilkS")
		)
		(fp_line
			(start -0.7874 0.4064)
			(end -0.7874 -0.4064)
			(stroke
				(width 0.1524)
				(type default)
			)
			(layer "F.SilkS")
		)
		(fp_line
			(start 0.7874 -0.4064)
			(end 0.7874 0.4064)
			(stroke
				(width 0.1524)
				(type default)
			)
			(layer "F.SilkS")
		)
		(fp_line
			(start 0.7874 0.4064)
			(end -0.7874 0.4064)
			(stroke
				(width 0.1524)
				(type default)
			)
			(layer "F.SilkS")
		)
		(fp_line
			(start -0.67945 -0.305054)
			(end -0.12065 -0.305054)
			(stroke
				(width 0.1)
				(type default)
			)
			(layer "F.Fab")
		)
		(fp_line
			(start -0.67945 0.3048)
			(end -0.67945 -0.305054)
			(stroke
				(width 0.1)
				(type default)
			)
			(layer "F.Fab")
		)
		(fp_line
			(start -0.12065 -0.305054)
			(end -0.12065 -0.2794)
			(stroke
				(width 0.1)
				(type default)
			)
			(layer "F.Fab")
		)
		(fp_line
			(start -0.12065 -0.2794)
			(end 0.12065 -0.2794)
			(stroke
				(width 0.1)
				(type default)
			)
			(layer "F.Fab")
		)
		(fp_line
			(start -0.12065 0.2794)
			(end -0.12065 0.3048)
			(stroke
				(width 0.1)
				(type default)
			)
			(layer "F.Fab")
		)
		(fp_line
			(start -0.12065 0.3048)
			(end -0.67945 0.3048)
			(stroke
				(width 0.1)
				(type default)
			)
			(layer "F.Fab")
		)
		(fp_line
			(start 0.120396 0.2794)
			(end -0.12065 0.2794)
			(stroke
				(width 0.1)
				(type default)
			)
			(layer "F.Fab")
		)
		(fp_line
			(start 0.120396 0.3048)
			(end 0.120396 0.2794)
			(stroke
				(width 0.1)
				(type default)
			)
			(layer "F.Fab")
		)
		(fp_line
			(start 0.12065 -0.3048)
			(end 0.67945 -0.3048)
			(stroke
				(width 0.1)
				(type default)
			)
			(layer "F.Fab")
		)
		(fp_line
			(start 0.12065 -0.2794)
			(end 0.12065 -0.3048)
			(stroke
				(width 0.1)
				(type default)
			)
			(layer "F.Fab")
		)
		(fp_line
			(start 0.67945 -0.3048)
			(end 0.67945 0.3048)
			(stroke
				(width 0.1)
				(type default)
			)
			(layer "F.Fab")
		)
		(fp_line
			(start 0.67945 0.3048)
			(end 0.120396 0.3048)
			(stroke
				(width 0.1)
				(type default)
			)
			(layer "F.Fab")
		)
		(pad "1" smd circle
			(at -0.40005 0)
			(size 0 0)
			(layers "F.Cu" "F.Mask" "F.Paste")
			(net "GND")
		)
		(pad "2" smd circle
			(at 0.40005 0)
			(size 0 0)
			(layers "F.Cu" "F.Mask" "F.Paste")
			(net "PVDDCR_CPU0_P1_LSET6")
		)
	)
)
